(kicad_pcb
	(version 20260206)
	(generator "pcbnew")
	(generator_version "10.0")
	(general
		(thickness 1.6)
		(legacy_teardrops no)
	)
	(paper "A4")
	(title_block
		(title "pdpb — Lightning_PDPB_BRD.brd")
		(comment 1 "Lightning (Wiwynn / Facebook NVMe JBOF) / footprints 359-365 of 1140")
	)
	(layers
		(0 "F.Cu" signal "TOP")
		(4 "In1.Cu" signal "L2GND")
		(6 "In2.Cu" signal "L3")
		(8 "In3.Cu" signal "L4VCC")
		(10 "In4.Cu" signal "L5VCC")
		(12 "In5.Cu" signal "L6")
		(14 "In6.Cu" signal "L7GND")
		(2 "B.Cu" signal "BOTTOM")
		(9 "F.Adhes" user "F.Adhesive")
		(11 "B.Adhes" user "B.Adhesive")
		(13 "F.Paste" user "Package Geometry/Pastemask Top")
		(15 "B.Paste" user "Package Geometry/Pastemask Bottom")
		(5 "F.SilkS" user "Ref Des/Silkscreen Top")
		(7 "B.SilkS" user "Ref Des/Silkscreen Bottom")
		(1 "F.Mask" user "Board Geometry/Soldermask Top")
		(3 "B.Mask" user "Board Geometry/Soldermask Bottom")
		(17 "Dwgs.User" user "User.Drawings")
		(19 "Cmts.User" user "User.Comments")
		(21 "Eco1.User" user "User.Eco1")
		(23 "Eco2.User" user "User.Eco2")
		(25 "Edge.Cuts" user "Board Geometry/Outline")
		(27 "Margin" user)
		(31 "F.CrtYd" user "Package Geometry/Place Bound Top")
		(29 "B.CrtYd" user "Package Geometry/Place Bound Bottom")
		(35 "F.Fab" user "Ref Des/Assembly Top")
		(33 "B.Fab" user "Ref Des/Assembly Bottom")
	)
	(footprint ""
		(layer "F.Cu")
		(at 29.3878 -10.6172 180)
		(property "Reference" "PC1233"
			(at 0 0 180)
			(layer "F.SilkS")
			(hide yes)
			(effects
				(font
					(size 1.27 1.27)
				)
			)
		)
		(property "Value" "SCD01U50V2KX-1GP"
			(at 1.1811 -2.7051 180)
			(unlocked yes)
			(layer "F.Fab")
			(hide yes)
			(effects
				(font
					(size 1.016 1.016)
					(thickness 0.1524)
				)
			)
		)
		(property "Device Type" "C402H22"
			(at 1.1811 -4.2291 180)
			(unlocked yes)
			(layer "F.Fab")
			(hide yes)
			(effects
				(font
					(size 1.016 1.016)
					(thickness 0.1524)
				)
			)
		)
		(duplicate_pad_numbers_are_jumpers no)
		(fp_rect
			(start -0.4318 0.9525)
			(end 0.4318 -0.9525)
			(stroke
				(width 0)
				(type default)
			)
			(fill no)
			(layer "F.CrtYd")
		)
		(fp_rect
			(start -0.4318 0.9525)
			(end 0.4318 -0.9525)
			(stroke
				(width 0)
				(type default)
			)
			(fill no)
			(layer "F.Fab")
		)
		(pad "1" smd custom
			(at 0 -0.4445 180)
			(size 0.1524 0.1524)
			(layers "F.Cu" "F.Mask" "F.Paste")
			(net "P12V_SSD14")
			(options
				(clearance outline)
				(anchor circle)
			)
			(primitives
				(gr_poly
					(pts
						(arc
							(start 0.3048 -0.2032)
							(mid 0.275042 -0.275042)
							(end 0.2032 -0.3048)
						)
						(arc
							(start -0.2032 -0.3048)
							(mid -0.275042 -0.275042)
							(end -0.3048 -0.2032)
						)
						(arc
							(start -0.3048 0.2032)
							(mid -0.275042 0.275042)
							(end -0.2032 0.3048)
						)
						(arc
							(start 0.2032 0.3048)
							(mid 0.275042 0.275042)
							(end 0.3048 0.2032)
						)
					)
					(width 0)
					(fill yes)
				)
			)
		)
		(pad "2" smd custom
			(at 0 0.4445 180)
			(size 0.1524 0.1524)
			(layers "F.Cu" "F.Mask" "F.Paste")
			(net "GND")
			(options
				(clearance outline)
				(anchor circle)
			)
			(primitives
				(gr_poly
					(pts
						(arc
							(start 0.3048 -0.2032)
							(mid 0.275042 -0.275042)
							(end 0.2032 -0.3048)
						)
						(arc
							(start -0.2032 -0.3048)
							(mid -0.275042 -0.275042)
							(end -0.3048 -0.2032)
						)
						(arc
							(start -0.3048 0.2032)
							(mid -0.275042 0.275042)
							(end -0.2032 0.3048)
						)
						(arc
							(start 0.2032 0.3048)
							(mid 0.275042 0.275042)
							(end 0.3048 0.2032)
						)
					)
					(width 0)
					(fill yes)
				)
			)
		)
	)
	(footprint ""
		(layer "F.Cu")
		(at 37.87775 -102.64775 180)
		(property "Reference" "R9773"
			(at 0 0 180)
			(layer "F.SilkS")
			(hide yes)
			(effects
				(font
					(size 1.27 1.27)
				)
			)
		)
		(property "Value" "4K7R2J-2-GP"
			(at 0.064008 -3.993896 180)
			(unlocked yes)
			(layer "F.Fab")
			(hide yes)
			(effects
				(font
					(size 1.016 1.016)
					(thickness 0.1524)
				)
			)
		)
		(property "Device Type" "R402H16"
			(at 0.064008 -5.517896 180)
			(unlocked yes)
			(layer "F.Fab")
			(hide yes)
			(effects
				(font
					(size 1.016 1.016)
					(thickness 0.1524)
				)
			)
		)
		(duplicate_pad_numbers_are_jumpers no)
		(fp_line
			(start 0.508 -0.9398)
			(end -0.508 -0.9398)
			(stroke
				(width 0.1524)
				(type default)
			)
			(layer "F.SilkS")
		)
		(fp_line
			(start -0.508 -0.9398)
			(end -0.508 0.9398)
			(stroke
				(width 0.1524)
				(type default)
			)
			(layer "F.SilkS")
		)
		(fp_rect
			(start -0.508 0.9398)
			(end 0.508 -0.9398)
			(stroke
				(width 0)
				(type default)
			)
			(fill no)
			(layer "F.CrtYd")
		)
		(fp_rect
			(start -0.508 0.9398)
			(end 0.508 -0.9398)
			(stroke
				(width 0)
				(type default)
			)
			(fill no)
			(layer "F.Fab")
		)
		(pad "1" smd custom
			(at 0 -0.4445 180)
			(size 0.1397 0.1397)
			(layers "F.Cu" "F.Mask" "F.Paste")
			(net "SSD13_PWREN")
			(options
				(clearance outline)
				(anchor circle)
			)
			(primitives
				(gr_poly
					(pts
						(arc
							(start -0.1778 -0.2794)
							(mid -0.249642 -0.249642)
							(end -0.2794 -0.1778)
						)
						(arc
							(start -0.2794 0.1778)
							(mid -0.249642 0.249642)
							(end -0.1778 0.2794)
						)
						(arc
							(start 0.1778 0.2794)
							(mid 0.249642 0.249642)
							(end 0.2794 0.1778)
						)
						(arc
							(start 0.2794 -0.1778)
							(mid 0.249642 -0.249642)
							(end 0.1778 -0.2794)
						)
					)
					(width 0)
					(fill yes)
				)
			)
		)
		(pad "2" smd custom
			(at 0 0.4445 180)
			(size 0.1397 0.1397)
			(layers "F.Cu" "F.Mask" "F.Paste")
			(net "GND")
			(options
				(clearance outline)
				(anchor circle)
			)
			(primitives
				(gr_poly
					(pts
						(arc
							(start -0.1778 -0.2794)
							(mid -0.249642 -0.249642)
							(end -0.2794 -0.1778)
						)
						(arc
							(start -0.2794 0.1778)
							(mid -0.249642 0.249642)
							(end -0.1778 0.2794)
						)
						(arc
							(start 0.1778 0.2794)
							(mid 0.249642 0.249642)
							(end 0.2794 0.1778)
						)
						(arc
							(start 0.2794 -0.1778)
							(mid 0.249642 -0.249642)
							(end 0.1778 -0.2794)
						)
					)
					(width 0)
					(fill yes)
				)
			)
		)
	)
	(footprint ""
		(layer "F.Cu")
		(at 73.025 -454.66 180)
		(property "Reference" "R348"
			(at 0 0 180)
			(layer "F.SilkS")
			(hide yes)
			(effects
				(font
					(size 1.27 1.27)
				)
			)
		)
		(property "Value" "4K7R2F-GP"
			(at 0.064008 -3.993896 180)
			(unlocked yes)
			(layer "F.Fab")
			(hide yes)
			(effects
				(font
					(size 1.016 1.016)
					(thickness 0.1524)
				)
			)
		)
		(property "Device Type" "R402H16"
			(at 0.064008 -5.517896 180)
			(unlocked yes)
			(layer "F.Fab")
			(hide yes)
			(effects
				(font
					(size 1.016 1.016)
					(thickness 0.1524)
				)
			)
		)
		(duplicate_pad_numbers_are_jumpers no)
		(fp_line
			(start 0.508 -0.9398)
			(end -0.508 -0.9398)
			(stroke
				(width 0.1524)
				(type default)
			)
			(layer "F.SilkS")
		)
		(fp_line
			(start -0.508 -0.9398)
			(end -0.508 0.9398)
			(stroke
				(width 0.1524)
				(type default)
			)
			(layer "F.SilkS")
		)
		(fp_rect
			(start -0.508 0.9398)
			(end 0.508 -0.9398)
			(stroke
				(width 0)
				(type default)
			)
			(fill no)
			(layer "F.CrtYd")
		)
		(fp_rect
			(start -0.508 0.9398)
			(end 0.508 -0.9398)
			(stroke
				(width 0)
				(type default)
			)
			(fill no)
			(layer "F.Fab")
		)
		(pad "1" smd custom
			(at 0 -0.4445 180)
			(size 0.1397 0.1397)
			(layers "F.Cu" "F.Mask" "F.Paste")
			(net "EEPROM_A0")
			(options
				(clearance outline)
				(anchor circle)
			)
			(primitives
				(gr_poly
					(pts
						(arc
							(start -0.1778 -0.2794)
							(mid -0.249642 -0.249642)
							(end -0.2794 -0.1778)
						)
						(arc
							(start -0.2794 0.1778)
							(mid -0.249642 0.249642)
							(end -0.1778 0.2794)
						)
						(arc
							(start 0.1778 0.2794)
							(mid 0.249642 0.249642)
							(end 0.2794 0.1778)
						)
						(arc
							(start 0.2794 -0.1778)
							(mid 0.249642 -0.249642)
							(end 0.1778 -0.2794)
						)
					)
					(width 0)
					(fill yes)
				)
			)
		)
		(pad "2" smd custom
			(at 0 0.4445 180)
			(size 0.1397 0.1397)
			(layers "F.Cu" "F.Mask" "F.Paste")
			(net "GND")
			(options
				(clearance outline)
				(anchor circle)
			)
			(primitives
				(gr_poly
					(pts
						(arc
							(start -0.1778 -0.2794)
							(mid -0.249642 -0.249642)
							(end -0.2794 -0.1778)
						)
						(arc
							(start -0.2794 0.1778)
							(mid -0.249642 0.249642)
							(end -0.1778 0.2794)
						)
						(arc
							(start 0.1778 0.2794)
							(mid 0.249642 0.249642)
							(end 0.2794 0.1778)
						)
						(arc
							(start 0.2794 -0.1778)
							(mid 0.249642 -0.249642)
							(end 0.1778 -0.2794)
						)
					)
					(width 0)
					(fill yes)
				)
			)
		)
	)
	(footprint ""
		(layer "F.Cu")
		(at 37.2618 -314.3504 90)
		(property "Reference" "R149"
			(at 0 0 90)
			(layer "F.SilkS")
			(hide yes)
			(effects
				(font
					(size 1.27 1.27)
				)
			)
		)
		(property "Value" "4K7R2J-2-GP"
			(at 0.064008 -3.993896 90)
			(unlocked yes)
			(layer "F.Fab")
			(hide yes)
			(effects
				(font
					(size 1.016 1.016)
					(thickness 0.1524)
				)
			)
		)
		(property "Device Type" "R402H16"
			(at 0.064008 -5.517896 90)
			(unlocked yes)
			(layer "F.Fab")
			(hide yes)
			(effects
				(font
					(size 1.016 1.016)
					(thickness 0.1524)
				)
			)
		)
		(duplicate_pad_numbers_are_jumpers no)
		(fp_line
			(start 0.508 -0.9398)
			(end -0.508 -0.9398)
			(stroke
				(width 0.1524)
				(type default)
			)
			(layer "F.SilkS")
		)
		(fp_line
			(start -0.508 -0.9398)
			(end -0.508 0.9398)
			(stroke
				(width 0.1524)
				(type default)
			)
			(layer "F.SilkS")
		)
		(fp_rect
			(start -0.508 0.9398)
			(end 0.508 -0.9398)
			(stroke
				(width 0)
				(type default)
			)
			(fill no)
			(layer "F.CrtYd")
		)
		(fp_rect
			(start -0.508 0.9398)
			(end 0.508 -0.9398)
			(stroke
				(width 0)
				(type default)
			)
			(fill no)
			(layer "F.Fab")
		)
		(pad "1" smd custom
			(at 0 -0.4445 90)
			(size 0.1397 0.1397)
			(layers "F.Cu" "F.Mask" "F.Paste")
			(net "P12V")
			(options
				(clearance outline)
				(anchor circle)
			)
			(primitives
				(gr_poly
					(pts
						(arc
							(start -0.1778 -0.2794)
							(mid -0.249642 -0.249642)
							(end -0.2794 -0.1778)
						)
						(arc
							(start -0.2794 0.1778)
							(mid -0.249642 0.249642)
							(end -0.1778 0.2794)
						)
						(arc
							(start 0.1778 0.2794)
							(mid 0.249642 0.249642)
							(end 0.2794 0.1778)
						)
						(arc
							(start 0.2794 -0.1778)
							(mid 0.249642 -0.249642)
							(end 0.1778 -0.2794)
						)
					)
					(width 0)
					(fill yes)
				)
			)
		)
		(pad "2" smd custom
			(at 0 0.4445 90)
			(size 0.1397 0.1397)
			(layers "F.Cu" "F.Mask" "F.Paste")
			(net "SW_SSD11_R")
			(options
				(clearance outline)
				(anchor circle)
			)
			(primitives
				(gr_poly
					(pts
						(arc
							(start -0.1778 -0.2794)
							(mid -0.249642 -0.249642)
							(end -0.2794 -0.1778)
						)
						(arc
							(start -0.2794 0.1778)
							(mid -0.249642 0.249642)
							(end -0.1778 0.2794)
						)
						(arc
							(start 0.1778 0.2794)
							(mid 0.249642 0.249642)
							(end 0.2794 0.1778)
						)
						(arc
							(start 0.2794 -0.1778)
							(mid 0.249642 -0.249642)
							(end 0.1778 -0.2794)
						)
					)
					(width 0)
					(fill yes)
				)
			)
		)
	)
	(footprint ""
		(layer "F.Cu")
		(at 85.471 -209.042 -90)
		(property "Reference" "PR9040"
			(at 0 0 270)
			(layer "F.SilkS")
			(hide yes)
			(effects
				(font
					(size 1.27 1.27)
				)
			)
		)
		(property "Value" "4K7R2F-GP"
			(at 0.064008 -3.993896 270)
			(unlocked yes)
			(layer "F.Fab")
			(hide yes)
			(effects
				(font
					(size 1.016 1.016)
					(thickness 0.1524)
				)
			)
		)
		(property "Device Type" "R402H16"
			(at 0.064008 -5.517896 270)
			(unlocked yes)
			(layer "F.Fab")
			(hide yes)
			(effects
				(font
					(size 1.016 1.016)
					(thickness 0.1524)
				)
			)
		)
		(duplicate_pad_numbers_are_jumpers no)
		(fp_line
			(start -0.508 -0.9398)
			(end -0.508 0.9398)
			(stroke
				(width 0.1524)
				(type default)
			)
			(layer "F.SilkS")
		)
		(fp_line
			(start 0.508 -0.9398)
			(end -0.508 -0.9398)
			(stroke
				(width 0.1524)
				(type default)
			)
			(layer "F.SilkS")
		)
		(fp_rect
			(start -0.508 0.9398)
			(end 0.508 -0.9398)
			(stroke
				(width 0)
				(type default)
			)
			(fill no)
			(layer "F.CrtYd")
		)
		(fp_rect
			(start -0.508 0.9398)
			(end 0.508 -0.9398)
			(stroke
				(width 0)
				(type default)
			)
			(fill no)
			(layer "F.Fab")
		)
		(pad "1" smd custom
			(at 0 -0.4445 270)
			(size 0.1397 0.1397)
			(layers "F.Cu" "F.Mask" "F.Paste")
			(net "CLK_BUF_EU3_SMB_A0_TRI")
			(options
				(clearance outline)
				(anchor circle)
			)
			(primitives
				(gr_poly
					(pts
						(arc
							(start -0.1778 -0.2794)
							(mid -0.249642 -0.249642)
							(end -0.2794 -0.1778)
						)
						(arc
							(start -0.2794 0.1778)
							(mid -0.249642 0.249642)
							(end -0.1778 0.2794)
						)
						(arc
							(start 0.1778 0.2794)
							(mid 0.249642 0.249642)
							(end 0.2794 0.1778)
						)
						(arc
							(start 0.2794 -0.1778)
							(mid 0.249642 -0.249642)
							(end 0.1778 -0.2794)
						)
					)
					(width 0)
					(fill yes)
				)
			)
		)
		(pad "2" smd custom
			(at 0 0.4445 270)
			(size 0.1397 0.1397)
			(layers "F.Cu" "F.Mask" "F.Paste")
			(net "GND")
			(options
				(clearance outline)
				(anchor circle)
			)
			(primitives
				(gr_poly
					(pts
						(arc
							(start -0.1778 -0.2794)
							(mid -0.249642 -0.249642)
							(end -0.2794 -0.1778)
						)
						(arc
							(start -0.2794 0.1778)
							(mid -0.249642 0.249642)
							(end -0.1778 0.2794)
						)
						(arc
							(start 0.1778 0.2794)
							(mid 0.249642 0.249642)
							(end 0.2794 0.1778)
						)
						(arc
							(start 0.2794 -0.1778)
							(mid 0.249642 -0.249642)
							(end 0.1778 -0.2794)
						)
					)
					(width 0)
					(fill yes)
				)
			)
		)
	)
	(footprint ""
		(layer "F.Cu")
		(at 71.0311 -366.522)
		(property "Reference" "SR983"
			(at 0 0 0)
			(layer "F.SilkS")
			(hide yes)
			(effects
				(font
					(size 1.27 1.27)
				)
			)
		)
		(property "Value" "2KR2F-3-GP"
			(at 0.064008 -3.993896 0)
			(unlocked yes)
			(layer "F.Fab")
			(hide yes)
			(effects
				(font
					(size 1.016 1.016)
					(thickness 0.1524)
				)
			)
		)
		(property "Device Type" "R402H16"
			(at 0.064008 -5.517896 0)
			(unlocked yes)
			(layer "F.Fab")
			(hide yes)
			(effects
				(font
					(size 1.016 1.016)
					(thickness 0.1524)
				)
			)
		)
		(duplicate_pad_numbers_are_jumpers no)
		(fp_line
			(start -0.508 -0.9398)
			(end -0.508 0.9398)
			(stroke
				(width 0.1524)
				(type default)
			)
			(layer "F.SilkS")
		)
		(fp_line
			(start 0.508 -0.9398)
			(end -0.508 -0.9398)
			(stroke
				(width 0.1524)
				(type default)
			)
			(layer "F.SilkS")
		)
		(fp_rect
			(start -0.508 0.9398)
			(end 0.508 -0.9398)
			(stroke
				(width 0)
				(type default)
			)
			(fill no)
			(layer "F.CrtYd")
		)
		(fp_rect
			(start -0.508 0.9398)
			(end 0.508 -0.9398)
			(stroke
				(width 0)
				(type default)
			)
			(fill no)
			(layer "F.Fab")
		)
		(pad "1" smd custom
			(at 0 -0.4445)
			(size 0.1397 0.1397)
			(layers "F.Cu" "F.Mask" "F.Paste")
			(net "P3V3")
			(options
				(clearance outline)
				(anchor circle)
			)
			(primitives
				(gr_poly
					(pts
						(arc
							(start -0.1778 -0.2794)
							(mid -0.249642 -0.249642)
							(end -0.2794 -0.1778)
						)
						(arc
							(start -0.2794 0.1778)
							(mid -0.249642 0.249642)
							(end -0.1778 0.2794)
						)
						(arc
							(start 0.1778 0.2794)
							(mid 0.249642 0.249642)
							(end 0.2794 0.1778)
						)
						(arc
							(start 0.2794 -0.1778)
							(mid 0.249642 -0.249642)
							(end 0.1778 -0.2794)
						)
					)
					(width 0)
					(fill yes)
				)
			)
		)
		(pad "2" smd custom
			(at 0 0.4445)
			(size 0.1397 0.1397)
			(layers "F.Cu" "F.Mask" "F.Paste")
			(net "SCL_DR6")
			(options
				(clearance outline)
				(anchor circle)
			)
			(primitives
				(gr_poly
					(pts
						(arc
							(start -0.1778 -0.2794)
							(mid -0.249642 -0.249642)
							(end -0.2794 -0.1778)
						)
						(arc
							(start -0.2794 0.1778)
							(mid -0.249642 0.249642)
							(end -0.1778 0.2794)
						)
						(arc
							(start 0.1778 0.2794)
							(mid 0.249642 0.249642)
							(end 0.2794 0.1778)
						)
						(arc
							(start 0.2794 -0.1778)
							(mid 0.249642 -0.249642)
							(end 0.1778 -0.2794)
						)
					)
					(width 0)
					(fill yes)
				)
			)
		)
	)
	(footprint ""
		(layer "F.Cu")
		(at 206.67345 -301.94885 90)
		(property "Reference" "R9793"
			(at 0 0 90)
			(layer "F.SilkS")
			(hide yes)
			(effects
				(font
					(size 1.27 1.27)
				)
			)
		)
		(property "Value" "1KR2J-1-GP"
			(at 0.064008 -3.993896 90)
			(unlocked yes)
			(layer "F.Fab")
			(hide yes)
			(effects
				(font
					(size 1.016 1.016)
					(thickness 0.1524)
				)
			)
		)
		(property "Device Type" "R402H16"
			(at 0.064008 -5.517896 90)
			(unlocked yes)
			(layer "F.Fab")
			(hide yes)
			(effects
				(font
					(size 1.016 1.016)
					(thickness 0.1524)
				)
			)
		)
		(duplicate_pad_numbers_are_jumpers no)
		(fp_line
			(start 0.508 -0.9398)
			(end -0.508 -0.9398)
			(stroke
				(width 0.1524)
				(type default)
			)
			(layer "F.SilkS")
		)
		(fp_line
			(start -0.508 -0.9398)
			(end -0.508 0.9398)
			(stroke
				(width 0.1524)
				(type default)
			)
			(layer "F.SilkS")
		)
		(fp_rect
			(start -0.508 0.9398)
			(end 0.508 -0.9398)
			(stroke
				(width 0)
				(type default)
			)
			(fill no)
			(layer "F.CrtYd")
		)
		(fp_rect
			(start -0.508 0.9398)
			(end 0.508 -0.9398)
			(stroke
				(width 0)
				(type default)
			)
			(fill no)
			(layer "F.Fab")
		)
		(pad "1" smd custom
			(at 0 -0.4445 90)
			(size 0.1397 0.1397)
			(layers "F.Cu" "F.Mask" "F.Paste")
			(net "SSD2_PWREN")
			(options
				(clearance outline)
				(anchor circle)
			)
			(primitives
				(gr_poly
					(pts
						(arc
							(start -0.1778 -0.2794)
							(mid -0.249642 -0.249642)
							(end -0.2794 -0.1778)
						)
						(arc
							(start -0.2794 0.1778)
							(mid -0.249642 0.249642)
							(end -0.1778 0.2794)
						)
						(arc
							(start 0.1778 0.2794)
							(mid 0.249642 0.249642)
							(end 0.2794 0.1778)
						)
						(arc
							(start 0.2794 -0.1778)
							(mid 0.249642 -0.249642)
							(end 0.1778 -0.2794)
						)
					)
					(width 0)
					(fill yes)
				)
			)
		)
		(pad "2" smd custom
			(at 0 0.4445 90)
			(size 0.1397 0.1397)
			(layers "F.Cu" "F.Mask" "F.Paste")
			(net "SSD2_PWREN_R")
			(options
				(clearance outline)
				(anchor circle)
			)
			(primitives
				(gr_poly
					(pts
						(arc
							(start -0.1778 -0.2794)
							(mid -0.249642 -0.249642)
							(end -0.2794 -0.1778)
						)
						(arc
							(start -0.2794 0.1778)
							(mid -0.249642 0.249642)
							(end -0.1778 0.2794)
						)
						(arc
							(start 0.1778 0.2794)
							(mid 0.249642 0.249642)
							(end 0.2794 0.1778)
						)
						(arc
							(start 0.2794 -0.1778)
							(mid 0.249642 -0.249642)
							(end 0.1778 -0.2794)
						)
					)
					(width 0)
					(fill yes)
				)
			)
		)
	)
)
